(kicad_pcb
	(version 20260206)
	(generator "pcbnew")
	(generator_version "10.0")
	(general
		(thickness 1.6)
		(legacy_teardrops no)
	)
	(paper "A4")
	(title_block
		(title "01162023_DA0F0TEBIF0_F0T_Expander_BD_F_brd_V02_OCP.brd")
		(comment 1 "Grand Teton / footprints 6526-6532 of 9728")
	)
	(layers
		(0 "F.Cu" signal "TOP")
		(4 "In1.Cu" signal "GND")
		(6 "In2.Cu" signal "VCC")
		(8 "In3.Cu" signal "VCC1")
		(10 "In4.Cu" signal "GND1")
		(12 "In5.Cu" signal "IN1")
		(14 "In6.Cu" signal "GND2")
		(16 "In7.Cu" signal "IN2")
		(18 "In8.Cu" signal "GND3")
		(20 "In9.Cu" signal "IN3")
		(22 "In10.Cu" signal "GND4")
		(24 "In11.Cu" signal "IN4")
		(26 "In12.Cu" signal "GND5")
		(28 "In13.Cu" signal "IN5")
		(30 "In14.Cu" signal "GND6")
		(32 "In15.Cu" signal "IN6")
		(34 "In16.Cu" signal "GND7")
		(2 "B.Cu" signal "BOTTOM")
		(9 "F.Adhes" user "F.Adhesive")
		(11 "B.Adhes" user "B.Adhesive")
		(13 "F.Paste" user "Package Geometry/Pastemask Top")
		(15 "B.Paste" user "Package Geometry/Pastemask Bottom")
		(5 "F.SilkS" user "Ref Des/Silkscreen Top")
		(7 "B.SilkS" user "Ref Des/Silkscreen Bottom")
		(1 "F.Mask" user "Board Geometry/Soldermask Top")
		(3 "B.Mask" user "Board Geometry/Soldermask Bottom")
		(17 "Dwgs.User" user "User.Drawings")
		(19 "Cmts.User" user "User.Comments")
		(21 "Eco1.User" user "User.Eco1")
		(23 "Eco2.User" user "User.Eco2")
		(25 "Edge.Cuts" user "Board Geometry/Outline")
		(27 "Margin" user)
		(31 "F.CrtYd" user "Package Geometry/Place Bound Top")
		(29 "B.CrtYd" user "Package Geometry/Place Bound Bottom")
		(35 "F.Fab" user "Ref Des/Assembly Top")
		(33 "B.Fab" user "Ref Des/Assembly Bottom")
	)
	(footprint ""
		(layer "F.Cu")
		(at 131.242816 -70.844918 -90)
		(property "Reference" "PD102"
			(at 3.839718 2.158746 90)
			(unlocked yes)
			(layer "F.SilkS")
			(effects
				(font
					(size 0.7874 0.5842)
					(thickness 0.1524)
				)
				(justify left)
			)
		)
		(property "Value" ""
			(at 0 0 270)
			(layer "F.Fab")
			(effects
				(font
					(size 1.27 1.27)
				)
			)
		)
		(duplicate_pad_numbers_are_jumpers no)
		(fp_line
			(start -3.400044 1.459992)
			(end -3.400044 -1.459992)
			(stroke
				(width 0.1524)
				(type default)
			)
			(layer "F.SilkS")
		)
		(fp_line
			(start 4.107942 1.459992)
			(end -3.400044 1.459992)
			(stroke
				(width 0.1524)
				(type default)
			)
			(layer "F.SilkS")
		)
		(fp_line
			(start -3.400044 -1.459992)
			(end 4.107942 -1.459992)
			(stroke
				(width 0.1524)
				(type default)
			)
			(layer "F.SilkS")
		)
		(fp_line
			(start 4.107942 -1.459992)
			(end 4.107942 1.459992)
			(stroke
				(width 0.1524)
				(type default)
			)
			(layer "F.SilkS")
		)
		(fp_poly
			(pts
				(xy 4.107942 -1.459992) (xy 4.107942 1.459992) (xy 3.308096 1.459992) (xy 3.308096 -1.459992)
			)
			(stroke
				(width 0)
				(type default)
			)
			(fill yes)
			(layer "F.SilkS")
		)
		(fp_line
			(start -2.29997 1.459992)
			(end -2.29997 -1.459992)
			(stroke
				(width 0.1)
				(type default)
			)
			(layer "F.Fab")
		)
		(fp_line
			(start 2.29997 1.459992)
			(end -2.29997 1.459992)
			(stroke
				(width 0.1)
				(type default)
			)
			(layer "F.Fab")
		)
		(fp_line
			(start -2.29997 -1.459992)
			(end 2.29997 -1.459992)
			(stroke
				(width 0.1)
				(type default)
			)
			(layer "F.Fab")
		)
		(fp_line
			(start 2.29997 -1.459992)
			(end 2.29997 1.459992)
			(stroke
				(width 0.1)
				(type default)
			)
			(layer "F.Fab")
		)
		(fp_text user "-"
			(at 5.4102 0.29845 90)
			(unlocked yes)
			(layer "F.SilkS")
			(effects
				(font
					(size 1.905 1.4224)
					(thickness 0.1524)
				)
				(justify left)
			)
		)
		(fp_text user "+"
			(at -5.375656 -0.180848 270)
			(unlocked yes)
			(layer "F.SilkS")
			(effects
				(font
					(size 1.905 1.4224)
					(thickness 0.1524)
				)
				(justify left)
			)
		)
		(fp_text user "-"
			(at 5.4102 0.29845 90)
			(unlocked yes)
			(layer "F.Fab")
			(effects
				(font
					(size 1.905 1.4224)
					(thickness 0.1524)
				)
				(justify left)
			)
		)
		(fp_text user "+"
			(at -4.7752 -0.12065 270)
			(unlocked yes)
			(layer "F.Fab")
			(effects
				(font
					(size 1.905 1.4224)
					(thickness 0.1524)
				)
				(justify left)
			)
		)
		(pad "A" smd rect
			(at -1.999996 0)
			(size 1.7018 2.5146)
			(layers "F.Cu" "F.Mask" "F.Paste")
			(net "GND")
		)
		(pad "C" smd rect
			(at 1.999996 0)
			(size 1.7018 2.5146)
			(layers "F.Cu" "F.Mask" "F.Paste")
			(net "P12V_SSD4_R")
		)
	)
	(footprint ""
		(layer "F.Cu")
		(at 234.3023 -178.844194 180)
		(property "Reference" "R4257"
			(at 0 0 180)
			(layer "F.SilkS")
			(hide yes)
			(effects
				(font
					(size 1.27 1.27)
				)
			)
		)
		(property "Value" ""
			(at 0 0 180)
			(layer "F.Fab")
			(effects
				(font
					(size 1.27 1.27)
				)
			)
		)
		(duplicate_pad_numbers_are_jumpers no)
		(fp_line
			(start 0.7874 0.4064)
			(end -0.7874 0.4064)
			(stroke
				(width 0.1524)
				(type default)
			)
			(layer "F.SilkS")
		)
		(fp_line
			(start 0.7874 -0.4064)
			(end 0.7874 0.4064)
			(stroke
				(width 0.1524)
				(type default)
			)
			(layer "F.SilkS")
		)
		(fp_line
			(start -0.7874 0.4064)
			(end -0.7874 -0.4064)
			(stroke
				(width 0.1524)
				(type default)
			)
			(layer "F.SilkS")
		)
		(fp_line
			(start -0.7874 -0.4064)
			(end 0.7874 -0.4064)
			(stroke
				(width 0.1524)
				(type default)
			)
			(layer "F.SilkS")
		)
		(fp_line
			(start 0.67945 0.3048)
			(end 0.120396 0.3048)
			(stroke
				(width 0.1)
				(type default)
			)
			(layer "F.Fab")
		)
		(fp_line
			(start 0.67945 -0.3048)
			(end 0.67945 0.3048)
			(stroke
				(width 0.1)
				(type default)
			)
			(layer "F.Fab")
		)
		(fp_line
			(start 0.12065 -0.2794)
			(end 0.12065 -0.3048)
			(stroke
				(width 0.1)
				(type default)
			)
			(layer "F.Fab")
		)
		(fp_line
			(start 0.12065 -0.3048)
			(end 0.67945 -0.3048)
			(stroke
				(width 0.1)
				(type default)
			)
			(layer "F.Fab")
		)
		(fp_line
			(start 0.120396 0.3048)
			(end 0.120396 0.2794)
			(stroke
				(width 0.1)
				(type default)
			)
			(layer "F.Fab")
		)
		(fp_line
			(start 0.120396 0.2794)
			(end -0.12065 0.2794)
			(stroke
				(width 0.1)
				(type default)
			)
			(layer "F.Fab")
		)
		(fp_line
			(start -0.12065 0.3048)
			(end -0.67945 0.3048)
			(stroke
				(width 0.1)
				(type default)
			)
			(layer "F.Fab")
		)
		(fp_line
			(start -0.12065 0.2794)
			(end -0.12065 0.3048)
			(stroke
				(width 0.1)
				(type default)
			)
			(layer "F.Fab")
		)
		(fp_line
			(start -0.12065 -0.2794)
			(end 0.12065 -0.2794)
			(stroke
				(width 0.1)
				(type default)
			)
			(layer "F.Fab")
		)
		(fp_line
			(start -0.12065 -0.305054)
			(end -0.12065 -0.2794)
			(stroke
				(width 0.1)
				(type default)
			)
			(layer "F.Fab")
		)
		(fp_line
			(start -0.67945 0.3048)
			(end -0.67945 -0.305054)
			(stroke
				(width 0.1)
				(type default)
			)
			(layer "F.Fab")
		)
		(fp_line
			(start -0.67945 -0.305054)
			(end -0.12065 -0.305054)
			(stroke
				(width 0.1)
				(type default)
			)
			(layer "F.Fab")
		)
		(pad "1" smd circle
			(at -0.40005 0 180)
			(size 0 0)
			(layers "F.Cu" "F.Mask" "F.Paste")
			(net "RST_FPGA_BIC_R1_N")
		)
		(pad "2" smd circle
			(at 0.40005 0 180)
			(size 0 0)
			(layers "F.Cu" "F.Mask" "F.Paste")
			(net "RST_FPGA_BIC_R_N")
		)
	)
	(footprint ""
		(layer "F.Cu")
		(at 216.989914 -311.179972)
		(property "Reference" "H132"
			(at -2.095754 -4.7879 0)
			(unlocked yes)
			(layer "F.SilkS")
			(effects
				(font
					(size 0.7874 0.5842)
					(thickness 0.1524)
				)
				(justify left)
			)
		)
		(property "Value" ""
			(at 0 0 0)
			(layer "F.Fab")
			(effects
				(font
					(size 1.27 1.27)
				)
			)
		)
		(duplicate_pad_numbers_are_jumpers no)
		(pad "1" thru_hole circle
			(at 0 0)
			(size 6.5024 6.5024)
			(drill 3.2004)
			(layers "*.Cu" "*.Mask")
			(remove_unused_layers no)
			(net "GND")
			(clearance -1.397)
		)
	)
	(footprint ""
		(layer "F.Cu")
		(at 137.73785 -194.088512 90)
		(property "Reference" "Y4"
			(at -2.421382 -0.01905 0)
			(unlocked yes)
			(layer "F.SilkS")
			(effects
				(font
					(size 0.7874 0.5842)
					(thickness 0.1524)
				)
				(justify left)
			)
		)
		(property "Value" ""
			(at 0 0 90)
			(layer "F.Fab")
			(effects
				(font
					(size 1.27 1.27)
				)
			)
		)
		(duplicate_pad_numbers_are_jumpers no)
		(fp_line
			(start 1.6002 -1.9558)
			(end 1.6002 1.9558)
			(stroke
				(width 0.1524)
				(type default)
			)
			(layer "F.SilkS")
		)
		(fp_line
			(start -1.6002 -1.9558)
			(end 1.6002 -1.9558)
			(stroke
				(width 0.1524)
				(type default)
			)
			(layer "F.SilkS")
		)
		(fp_line
			(start 1.6002 1.9558)
			(end -1.6002 1.9558)
			(stroke
				(width 0.1524)
				(type default)
			)
			(layer "F.SilkS")
		)
		(fp_line
			(start -1.6002 1.9558)
			(end -1.6002 -1.9558)
			(stroke
				(width 0.1524)
				(type default)
			)
			(layer "F.SilkS")
		)
		(fp_poly
			(pts
				(xy -1.7145 -1.0668) (xy -2.8067 -1.651) (xy -2.8067 -0.5842)
			)
			(stroke
				(width 0)
				(type default)
			)
			(fill yes)
			(layer "F.SilkS")
		)
		(fp_line
			(start 1.299972 -1.649984)
			(end 1.299972 1.649984)
			(stroke
				(width 0.1)
				(type default)
			)
			(layer "F.Fab")
		)
		(fp_line
			(start -1.299972 -1.649984)
			(end 1.299972 -1.649984)
			(stroke
				(width 0.1)
				(type default)
			)
			(layer "F.Fab")
		)
		(fp_line
			(start 1.299972 1.649984)
			(end -1.299972 1.649984)
			(stroke
				(width 0.1)
				(type default)
			)
			(layer "F.Fab")
		)
		(fp_line
			(start -1.299972 1.649984)
			(end -1.299972 -1.649984)
			(stroke
				(width 0.1)
				(type default)
			)
			(layer "F.Fab")
		)
		(fp_poly
			(pts
				(xy -1.7145 -1.0668) (xy -2.8067 -1.651) (xy -2.8067 -0.5842)
			)
			(stroke
				(width 0)
				(type default)
			)
			(fill yes)
			(layer "F.Fab")
		)
		(pad "1" smd rect
			(at -0.849884 -1.100074 90)
			(size 1.2192 1.4224)
			(layers "F.Cu" "F.Mask" "F.Paste")
			(net "OSC_CLI_IN")
		)
		(pad "2" smd rect
			(at -0.849884 1.100074 90)
			(size 1.2192 1.4224)
			(layers "F.Cu" "F.Mask" "F.Paste")
			(net "GND")
		)
		(pad "3" smd rect
			(at 0.849884 1.100074 90)
			(size 1.2192 1.4224)
			(layers "F.Cu" "F.Mask" "F.Paste")
			(net "OSC_CLI_OUT")
		)
		(pad "4" smd rect
			(at 0.849884 -1.100074 90)
			(size 1.2192 1.4224)
			(layers "F.Cu" "F.Mask" "F.Paste")
			(net "GND")
		)
	)
	(footprint ""
		(layer "F.Cu")
		(at 310.810402 -18.61439 90)
		(property "Reference" "U136"
			(at -1.34239 2.372868 90)
			(unlocked yes)
			(layer "F.SilkS")
			(effects
				(font
					(size 0.7874 0.5842)
					(thickness 0.1524)
				)
				(justify left)
			)
		)
		(property "Value" ""
			(at 0 0 90)
			(layer "F.Fab")
			(effects
				(font
					(size 1.27 1.27)
				)
			)
		)
		(duplicate_pad_numbers_are_jumpers no)
		(fp_line
			(start 1.463548 -1.549908)
			(end 1.463548 1.549908)
			(stroke
				(width 0.1524)
				(type default)
			)
			(layer "F.SilkS")
		)
		(fp_line
			(start 0.762 -1.549908)
			(end 1.463548 -1.549908)
			(stroke
				(width 0.1524)
				(type default)
			)
			(layer "F.SilkS")
		)
		(fp_line
			(start -0.787908 -1.549908)
			(end 0 -0.762)
			(stroke
				(width 0.1524)
				(type default)
			)
			(layer "F.SilkS")
		)
		(fp_line
			(start -1.463548 -1.549908)
			(end -0.787908 -1.549908)
			(stroke
				(width 0.1524)
				(type default)
			)
			(layer "F.SilkS")
		)
		(fp_line
			(start 0 -0.762)
			(end 0.762 -1.549908)
			(stroke
				(width 0.1524)
				(type default)
			)
			(layer "F.SilkS")
		)
		(fp_line
			(start 1.463548 1.549908)
			(end -1.463548 1.549908)
			(stroke
				(width 0.1524)
				(type default)
			)
			(layer "F.SilkS")
		)
		(fp_line
			(start -1.463548 1.549908)
			(end -1.463548 -1.549908)
			(stroke
				(width 0.1524)
				(type default)
			)
			(layer "F.SilkS")
		)
		(fp_poly
			(pts
				(xy -3.4798 -1.359916) (xy -2.86004 -1.050036) (xy -3.4798 -0.740156)
			)
			(stroke
				(width 0)
				(type default)
			)
			(fill yes)
			(layer "F.SilkS")
		)
		(fp_line
			(start 1.549908 -1.549908)
			(end 1.549908 1.549908)
			(stroke
				(width 0.1)
				(type default)
			)
			(layer "F.Fab")
		)
		(fp_line
			(start -1.549908 -1.549908)
			(end 1.549908 -1.549908)
			(stroke
				(width 0.1)
				(type default)
			)
			(layer "F.Fab")
		)
		(fp_line
			(start 1.549908 1.549908)
			(end -1.549908 1.549908)
			(stroke
				(width 0.1)
				(type default)
			)
			(layer "F.Fab")
		)
		(fp_line
			(start -1.549908 1.549908)
			(end -1.549908 -1.549908)
			(stroke
				(width 0.1)
				(type default)
			)
			(layer "F.Fab")
		)
		(fp_poly
			(pts
				(xy -3.4798 -1.359916) (xy -2.86004 -1.050036) (xy -3.4798 -0.740156)
			)
			(stroke
				(width 0)
				(type default)
			)
			(fill yes)
			(layer "F.Fab")
		)
		(pad "1" smd rect
			(at -2.175002 -1.050036 180)
			(size 0.6096 1.1684)
			(layers "F.Cu" "F.Mask" "F.Paste")
			(net "P3V3_SSD10")
		)
		(pad "2" smd rect
			(at -2.175002 -0.32512 180)
			(size 0.4318 1.1684)
			(layers "F.Cu" "F.Mask" "F.Paste")
			(net "SMB_ISO_SSD10_SCL")
		)
		(pad "3" smd rect
			(at -2.175002 0.32512 180)
			(size 0.4318 1.1684)
			(layers "F.Cu" "F.Mask" "F.Paste")
			(net "SMB_ISO_SSD10_SDA")
		)
		(pad "4" smd rect
			(at -2.175002 1.050036 180)
			(size 0.6096 1.1684)
			(layers "F.Cu" "F.Mask" "F.Paste")
			(net "GND")
		)
		(pad "5" smd rect
			(at 2.175002 1.050036 180)
			(size 0.6096 1.1684)
			(layers "F.Cu" "F.Mask" "F.Paste")
			(net "SMB_SSD10_ISO_EN")
		)
		(pad "6" smd rect
			(at 2.175002 0.32512 180)
			(size 0.4318 1.1684)
			(layers "F.Cu" "F.Mask" "F.Paste")
			(net "SMB_BIC_I2C9_MUX1_SSD10_R_SDA")
		)
		(pad "7" smd rect
			(at 2.175002 -0.32512 180)
			(size 0.4318 1.1684)
			(layers "F.Cu" "F.Mask" "F.Paste")
			(net "SMB_BIC_I2C9_MUX1_SSD10_R_SCL")
		)
		(pad "8" smd rect
			(at 2.175002 -1.050036 180)
			(size 0.6096 1.1684)
			(layers "F.Cu" "F.Mask" "F.Paste")
			(net "P3V3_AUX")
		)
	)
	(footprint ""
		(layer "F.Cu")
		(at 393.669266 -80.356202 180)
		(property "Reference" "R1766"
			(at 0 0 180)
			(layer "F.SilkS")
			(hide yes)
			(effects
				(font
					(size 1.27 1.27)
				)
			)
		)
		(property "Value" ""
			(at 0 0 180)
			(layer "F.Fab")
			(effects
				(font
					(size 1.27 1.27)
				)
			)
		)
		(duplicate_pad_numbers_are_jumpers no)
		(fp_line
			(start 0.7874 0.4064)
			(end -0.7874 0.4064)
			(stroke
				(width 0.1524)
				(type default)
			)
			(layer "F.SilkS")
		)
		(fp_line
			(start 0.7874 -0.4064)
			(end 0.7874 0.4064)
			(stroke
				(width 0.1524)
				(type default)
			)
			(layer "F.SilkS")
		)
		(fp_line
			(start -0.7874 0.4064)
			(end -0.7874 -0.4064)
			(stroke
				(width 0.1524)
				(type default)
			)
			(layer "F.SilkS")
		)
		(fp_line
			(start -0.7874 -0.4064)
			(end 0.7874 -0.4064)
			(stroke
				(width 0.1524)
				(type default)
			)
			(layer "F.SilkS")
		)
		(fp_line
			(start 0.67945 0.3048)
			(end 0.120396 0.3048)
			(stroke
				(width 0.1)
				(type default)
			)
			(layer "F.Fab")
		)
		(fp_line
			(start 0.67945 -0.3048)
			(end 0.67945 0.3048)
			(stroke
				(width 0.1)
				(type default)
			)
			(layer "F.Fab")
		)
		(fp_line
			(start 0.12065 -0.2794)
			(end 0.12065 -0.3048)
			(stroke
				(width 0.1)
				(type default)
			)
			(layer "F.Fab")
		)
		(fp_line
			(start 0.12065 -0.3048)
			(end 0.67945 -0.3048)
			(stroke
				(width 0.1)
				(type default)
			)
			(layer "F.Fab")
		)
		(fp_line
			(start 0.120396 0.3048)
			(end 0.120396 0.2794)
			(stroke
				(width 0.1)
				(type default)
			)
			(layer "F.Fab")
		)
		(fp_line
			(start 0.120396 0.2794)
			(end -0.12065 0.2794)
			(stroke
				(width 0.1)
				(type default)
			)
			(layer "F.Fab")
		)
		(fp_line
			(start -0.12065 0.3048)
			(end -0.67945 0.3048)
			(stroke
				(width 0.1)
				(type default)
			)
			(layer "F.Fab")
		)
		(fp_line
			(start -0.12065 0.2794)
			(end -0.12065 0.3048)
			(stroke
				(width 0.1)
				(type default)
			)
			(layer "F.Fab")
		)
		(fp_line
			(start -0.12065 -0.2794)
			(end 0.12065 -0.2794)
			(stroke
				(width 0.1)
				(type default)
			)
			(layer "F.Fab")
		)
		(fp_line
			(start -0.12065 -0.305054)
			(end -0.12065 -0.2794)
			(stroke
				(width 0.1)
				(type default)
			)
			(layer "F.Fab")
		)
		(fp_line
			(start -0.67945 0.3048)
			(end -0.67945 -0.305054)
			(stroke
				(width 0.1)
				(type default)
			)
			(layer "F.Fab")
		)
		(fp_line
			(start -0.67945 -0.305054)
			(end -0.12065 -0.305054)
			(stroke
				(width 0.1)
				(type default)
			)
			(layer "F.Fab")
		)
		(pad "1" smd circle
			(at -0.40005 0 180)
			(size 0 0)
			(layers "F.Cu" "F.Mask" "F.Paste")
			(net "SMB_BIC_I2C6_MUX_SSD_8_15_ADC_R_SDA")
		)
		(pad "2" smd circle
			(at 0.40005 0 180)
			(size 0 0)
			(layers "F.Cu" "F.Mask" "F.Paste")
			(net "SMB_BIC_I2C6_MUX_SSD_8_15_ADC_SDA")
		)
	)
	(footprint ""
		(layer "F.Cu")
		(at 125.454156 -172.44949 90)
		(property "Reference" "C4501"
			(at 0 0 90)
			(layer "F.SilkS")
			(hide yes)
			(effects
				(font
					(size 1.27 1.27)
				)
			)
		)
		(property "Value" ""
			(at 0 0 90)
			(layer "F.Fab")
			(effects
				(font
					(size 1.27 1.27)
				)
			)
		)
		(duplicate_pad_numbers_are_jumpers no)
		(fp_line
			(start 0.7874 -0.4064)
			(end 0.7874 0.4064)
			(stroke
				(width 0.1524)
				(type default)
			)
			(layer "F.SilkS")
		)
		(fp_line
			(start -0.7874 -0.4064)
			(end 0.7874 -0.4064)
			(stroke
				(width 0.1524)
				(type default)
			)
			(layer "F.SilkS")
		)
		(fp_line
			(start 0.7874 0.4064)
			(end -0.7874 0.4064)
			(stroke
				(width 0.1524)
				(type default)
			)
			(layer "F.SilkS")
		)
		(fp_line
			(start -0.7874 0.4064)
			(end -0.7874 -0.4064)
			(stroke
				(width 0.1524)
				(type default)
			)
			(layer "F.SilkS")
		)
		(fp_line
			(start -0.12065 -0.305054)
			(end -0.12065 -0.2794)
			(stroke
				(width 0.1)
				(type default)
			)
			(layer "F.Fab")
		)
		(fp_line
			(start -0.67945 -0.305054)
			(end -0.12065 -0.305054)
			(stroke
				(width 0.1)
				(type default)
			)
			(layer "F.Fab")
		)
		(fp_line
			(start 0.67945 -0.3048)
			(end 0.67945 0.3048)
			(stroke
				(width 0.1)
				(type default)
			)
			(layer "F.Fab")
		)
		(fp_line
			(start 0.12065 -0.3048)
			(end 0.67945 -0.3048)
			(stroke
				(width 0.1)
				(type default)
			)
			(layer "F.Fab")
		)
		(fp_line
			(start 0.12065 -0.2794)
			(end 0.12065 -0.3048)
			(stroke
				(width 0.1)
				(type default)
			)
			(layer "F.Fab")
		)
		(fp_line
			(start -0.12065 -0.2794)
			(end 0.12065 -0.2794)
			(stroke
				(width 0.1)
				(type default)
			)
			(layer "F.Fab")
		)
		(fp_line
			(start 0.120396 0.2794)
			(end -0.12065 0.2794)
			(stroke
				(width 0.1)
				(type default)
			)
			(layer "F.Fab")
		)
		(fp_line
			(start -0.12065 0.2794)
			(end -0.12065 0.3048)
			(stroke
				(width 0.1)
				(type default)
			)
			(layer "F.Fab")
		)
		(fp_line
			(start 0.67945 0.3048)
			(end 0.120396 0.3048)
			(stroke
				(width 0.1)
				(type default)
			)
			(layer "F.Fab")
		)
		(fp_line
			(start 0.120396 0.3048)
			(end 0.120396 0.2794)
			(stroke
				(width 0.1)
				(type default)
			)
			(layer "F.Fab")
		)
		(fp_line
			(start -0.12065 0.3048)
			(end -0.67945 0.3048)
			(stroke
				(width 0.1)
				(type default)
			)
			(layer "F.Fab")
		)
		(fp_line
			(start -0.67945 0.3048)
			(end -0.67945 -0.305054)
			(stroke
				(width 0.1)
				(type default)
			)
			(layer "F.Fab")
		)
		(pad "1" smd circle
			(at -0.40005 0 90)
			(size 0 0)
			(layers "F.Cu" "F.Mask" "F.Paste")
			(net "NIC0_CLK_EN_R_N")
		)
		(pad "2" smd circle
			(at 0.40005 0 90)
			(size 0 0)
			(layers "F.Cu" "F.Mask" "F.Paste")
			(net "GND")
		)
	)
)
